# S9S_MB_2U (Grand Teton) — schematic netlist excerpt (pin names and nets, part order shuffled) for the footprints in the layout excerpt that follows; sources: Cadence DE-HDL packaged netlist, KiCad conversion of 03242023_DA0F0TMBIJ0_F0T_Motherboard_J_brd_V01_OCP.brd

C1257  Q_CAP  1UF 6.3V 10% EMPTY  pkg 0402  page 189 : A = P1V8_PCH_PLL_AUX ; B = GND
C74  Q_CAP  10UF 16V 10% X6S  pkg C0805  page 113 : A = P12V_S3_AUX_CPU1_NVDIMM ; B = GND
C1938  Q_CAP  10UF 6.3V 20% X6S  pkg C0402  page 217 : A = P3V3_AUX_FPGA_VCCIO0 ; B = GND

(kicad_pcb
	(version 20260206)
	(generator "pcbnew")
	(generator_version "10.0")
	(general
		(thickness 1.6)
		(legacy_teardrops no)
	)
	(paper "A4")
	(title_block
		(title "03242023_DA0F0TMBIJ0_F0T_Motherboard_J_brd_V01_OCP.brd")
		(comment 1 "Grand Teton / footprints 5068-5070 of 6105")
	)
	(layers
		(0 "F.Cu" signal "TOP")
		(4 "In1.Cu" signal "GND")
		(6 "In2.Cu" signal "IN1")
		(8 "In3.Cu" signal "GND1")
		(10 "In4.Cu" signal "IN2")
		(12 "In5.Cu" signal "GND2")
		(14 "In6.Cu" signal "IN3")
		(16 "In7.Cu" signal "GND3")
		(18 "In8.Cu" signal "VCC")
		(20 "In9.Cu" signal "VCC1")
		(22 "In10.Cu" signal "GND4")
		(24 "In11.Cu" signal "IN4")
		(26 "In12.Cu" signal "GND5")
		(28 "In13.Cu" signal "IN5")
		(30 "In14.Cu" signal "GND6")
		(32 "In15.Cu" signal "IN6")
		(34 "In16.Cu" signal "GND7")
		(2 "B.Cu" signal "BOTTOM")
		(9 "F.Adhes" user "F.Adhesive")
		(11 "B.Adhes" user "B.Adhesive")
		(13 "F.Paste" user "Package Geometry/Pastemask Top")
		(15 "B.Paste" user "Package Geometry/Pastemask Bottom")
		(5 "F.SilkS" user "Ref Des/Silkscreen Top")
		(7 "B.SilkS" user "Ref Des/Silkscreen Bottom")
		(1 "F.Mask" user "Board Geometry/Soldermask Top")
		(3 "B.Mask" user "Board Geometry/Soldermask Bottom")
		(17 "Dwgs.User" user "User.Drawings")
		(19 "Cmts.User" user "User.Comments")
		(21 "Eco1.User" user "User.Eco1")
		(23 "Eco2.User" user "User.Eco2")
		(25 "Edge.Cuts" user "Board Geometry/Outline")
		(27 "Margin" user)
		(31 "F.CrtYd" user "Package Geometry/Place Bound Top")
		(29 "B.CrtYd" user "Package Geometry/Place Bound Bottom")
		(35 "F.Fab" user "Ref Des/Assembly Top")
		(33 "B.Fab" user "Ref Des/Assembly Bottom")
	)
	(footprint ""
		(layer "B.Cu")
		(at 168.83888 -102.707948)
		(property "Reference" "C1938"
			(at 0 0 0)
			(layer "B.SilkS")
			(hide yes)
			(effects
				(font
					(size 1.27 1.27)
				)
				(justify mirror)
			)
		)
		(property "Value" ""
			(at 0 0 0)
			(layer "B.Fab")
			(effects
				(font
					(size 1.27 1.27)
				)
				(justify mirror)
			)
		)
		(duplicate_pad_numbers_are_jumpers no)
		(fp_line
			(start -0.7874 -0.4064)
			(end -0.7874 0.4064)
			(stroke
				(width 0.1524)
				(type default)
			)
			(layer "B.SilkS")
		)
		(fp_line
			(start -0.7874 0.4064)
			(end 0.7874 0.4064)
			(stroke
				(width 0.1524)
				(type default)
			)
			(layer "B.SilkS")
		)
		(fp_line
			(start 0.7874 -0.4064)
			(end -0.7874 -0.4064)
			(stroke
				(width 0.1524)
				(type default)
			)
			(layer "B.SilkS")
		)
		(fp_line
			(start 0.7874 0.4064)
			(end 0.7874 -0.4064)
			(stroke
				(width 0.1524)
				(type default)
			)
			(layer "B.SilkS")
		)
		(fp_line
			(start -0.67945 -0.3048)
			(end -0.67945 0.3048)
			(stroke
				(width 0.1)
				(type default)
			)
			(layer "B.Fab")
		)
		(fp_line
			(start -0.67945 0.3048)
			(end -0.120396 0.3048)
			(stroke
				(width 0.1)
				(type default)
			)
			(layer "B.Fab")
		)
		(fp_line
			(start -0.12065 -0.3048)
			(end -0.67945 -0.3048)
			(stroke
				(width 0.1)
				(type default)
			)
			(layer "B.Fab")
		)
		(fp_line
			(start -0.12065 -0.2794)
			(end -0.12065 -0.3048)
			(stroke
				(width 0.1)
				(type default)
			)
			(layer "B.Fab")
		)
		(fp_line
			(start -0.120396 0.2794)
			(end 0.12065 0.2794)
			(stroke
				(width 0.1)
				(type default)
			)
			(layer "B.Fab")
		)
		(fp_line
			(start -0.120396 0.3048)
			(end -0.120396 0.2794)
			(stroke
				(width 0.1)
				(type default)
			)
			(layer "B.Fab")
		)
		(fp_line
			(start 0.12065 -0.305054)
			(end 0.12065 -0.2794)
			(stroke
				(width 0.1)
				(type default)
			)
			(layer "B.Fab")
		)
		(fp_line
			(start 0.12065 -0.2794)
			(end -0.12065 -0.2794)
			(stroke
				(width 0.1)
				(type default)
			)
			(layer "B.Fab")
		)
		(fp_line
			(start 0.12065 0.2794)
			(end 0.12065 0.3048)
			(stroke
				(width 0.1)
				(type default)
			)
			(layer "B.Fab")
		)
		(fp_line
			(start 0.12065 0.3048)
			(end 0.67945 0.3048)
			(stroke
				(width 0.1)
				(type default)
			)
			(layer "B.Fab")
		)
		(fp_line
			(start 0.67945 -0.305054)
			(end 0.12065 -0.305054)
			(stroke
				(width 0.1)
				(type default)
			)
			(layer "B.Fab")
		)
		(fp_line
			(start 0.67945 0.3048)
			(end 0.67945 -0.305054)
			(stroke
				(width 0.1)
				(type default)
			)
			(layer "B.Fab")
		)
		(pad "1" smd circle
			(at 0.40005 0 180)
			(size 0 0)
			(layers "B.Cu" "B.Mask" "B.Paste")
			(net "P3V3_AUX_FPGA_VCCIO0")
		)
		(pad "2" smd circle
			(at -0.40005 0 180)
			(size 0 0)
			(layers "B.Cu" "B.Mask" "B.Paste")
			(net "GND")
		)
	)
	(footprint ""
		(layer "B.Cu")
		(at 342.453214 -52.202334 -90)
		(property "Reference" "C1257"
			(at 0 0 90)
			(layer "B.SilkS")
			(hide yes)
			(effects
				(font
					(size 1.27 1.27)
				)
				(justify mirror)
			)
		)
		(property "Value" ""
			(at 0 0 90)
			(layer "B.Fab")
			(effects
				(font
					(size 1.27 1.27)
				)
				(justify mirror)
			)
		)
		(duplicate_pad_numbers_are_jumpers no)
		(fp_line
			(start -0.7874 0.4064)
			(end 0.7874 0.4064)
			(stroke
				(width 0.1524)
				(type default)
			)
			(layer "B.SilkS")
		)
		(fp_line
			(start 0.7874 0.4064)
			(end 0.7874 -0.4064)
			(stroke
				(width 0.1524)
				(type default)
			)
			(layer "B.SilkS")
		)
		(fp_line
			(start -0.7874 -0.4064)
			(end -0.7874 0.4064)
			(stroke
				(width 0.1524)
				(type default)
			)
			(layer "B.SilkS")
		)
		(fp_line
			(start 0.7874 -0.4064)
			(end -0.7874 -0.4064)
			(stroke
				(width 0.1524)
				(type default)
			)
			(layer "B.SilkS")
		)
		(fp_line
			(start -0.67945 0.3048)
			(end -0.120396 0.3048)
			(stroke
				(width 0.1)
				(type default)
			)
			(layer "B.Fab")
		)
		(fp_line
			(start -0.120396 0.3048)
			(end -0.120396 0.2794)
			(stroke
				(width 0.1)
				(type default)
			)
			(layer "B.Fab")
		)
		(fp_line
			(start 0.12065 0.3048)
			(end 0.67945 0.3048)
			(stroke
				(width 0.1)
				(type default)
			)
			(layer "B.Fab")
		)
		(fp_line
			(start 0.67945 0.3048)
			(end 0.67945 -0.305054)
			(stroke
				(width 0.1)
				(type default)
			)
			(layer "B.Fab")
		)
		(fp_line
			(start -0.120396 0.2794)
			(end 0.12065 0.2794)
			(stroke
				(width 0.1)
				(type default)
			)
			(layer "B.Fab")
		)
		(fp_line
			(start 0.12065 0.2794)
			(end 0.12065 0.3048)
			(stroke
				(width 0.1)
				(type default)
			)
			(layer "B.Fab")
		)
		(fp_line
			(start -0.12065 -0.2794)
			(end -0.12065 -0.3048)
			(stroke
				(width 0.1)
				(type default)
			)
			(layer "B.Fab")
		)
		(fp_line
			(start 0.12065 -0.2794)
			(end -0.12065 -0.2794)
			(stroke
				(width 0.1)
				(type default)
			)
			(layer "B.Fab")
		)
		(fp_line
			(start -0.67945 -0.3048)
			(end -0.67945 0.3048)
			(stroke
				(width 0.1)
				(type default)
			)
			(layer "B.Fab")
		)
		(fp_line
			(start -0.12065 -0.3048)
			(end -0.67945 -0.3048)
			(stroke
				(width 0.1)
				(type default)
			)
			(layer "B.Fab")
		)
		(fp_line
			(start 0.12065 -0.305054)
			(end 0.12065 -0.2794)
			(stroke
				(width 0.1)
				(type default)
			)
			(layer "B.Fab")
		)
		(fp_line
			(start 0.67945 -0.305054)
			(end 0.12065 -0.305054)
			(stroke
				(width 0.1)
				(type default)
			)
			(layer "B.Fab")
		)
		(pad "1" smd circle
			(at 0.40005 0 90)
			(size 0 0)
			(layers "B.Cu" "B.Mask" "B.Paste")
			(net "P1V8_PCH_PLL_AUX")
		)
		(pad "2" smd circle
			(at -0.40005 0 90)
			(size 0 0)
			(layers "B.Cu" "B.Mask" "B.Paste")
			(net "GND")
		)
	)
	(footprint ""
		(layer "B.Cu")
		(at 204.088746 -321.554856 -90)
		(property "Reference" "C74"
			(at 0 0 90)
			(layer "B.SilkS")
			(hide yes)
			(effects
				(font
					(size 1.27 1.27)
				)
				(justify mirror)
			)
		)
		(property "Value" ""
			(at 0 0 90)
			(layer "B.Fab")
			(effects
				(font
					(size 1.27 1.27)
				)
				(justify mirror)
			)
		)
		(duplicate_pad_numbers_are_jumpers no)
		(fp_line
			(start -1.524 0.762)
			(end 1.524 0.762)
			(stroke
				(width 0.1524)
				(type default)
			)
			(layer "B.SilkS")
		)
		(fp_line
			(start 1.524 0.762)
			(end 1.524 -0.762)
			(stroke
				(width 0.1524)
				(type default)
			)
			(layer "B.SilkS")
		)
		(fp_line
			(start -1.524 -0.762)
			(end -1.524 0.762)
			(stroke
				(width 0.1524)
				(type default)
			)
			(layer "B.SilkS")
		)
		(fp_line
			(start 1.524 -0.762)
			(end -1.524 -0.762)
			(stroke
				(width 0.1524)
				(type default)
			)
			(layer "B.SilkS")
		)
		(fp_line
			(start -1.1049 0.724916)
			(end -1.1049 -0.724916)
			(stroke
				(width 0.1)
				(type default)
			)
			(layer "B.Fab")
		)
		(fp_line
			(start 1.1049 0.724916)
			(end -1.1049 0.724916)
			(stroke
				(width 0.1)
				(type default)
			)
			(layer "B.Fab")
		)
		(fp_line
			(start -1.1049 -0.724916)
			(end 1.1049 -0.724916)
			(stroke
				(width 0.1)
				(type default)
			)
			(layer "B.Fab")
		)
		(fp_line
			(start 1.1049 -0.724916)
			(end 1.1049 0.724916)
			(stroke
				(width 0.1)
				(type default)
			)
			(layer "B.Fab")
		)
		(pad "1" smd rect
			(at 0.889 0 270)
			(size 1.016 1.27)
			(layers "B.Cu" "B.Mask" "B.Paste")
			(net "P12V_S3_AUX_CPU1_NVDIMM")
		)
		(pad "2" smd rect
			(at -0.889 0 270)
			(size 1.016 1.27)
			(layers "B.Cu" "B.Mask" "B.Paste")
			(net "GND")
		)
	)
)
